(kicad_pcb
	(version 20260206)
	(generator "pcbnew")
	(generator_version "10.0")
	(general
		(thickness 1.6)
		(legacy_teardrops no)
	)
	(paper "A4")
	(title_block
		(title "peb — Lightning_PEB_BRD.brd")
		(comment 1 "Lightning (Wiwynn / Facebook NVMe JBOF) / footprints 1139-1144 of 2563")
	)
	(layers
		(0 "F.Cu" signal "TOP")
		(4 "In1.Cu" signal "L2GND")
		(6 "In2.Cu" signal "L3")
		(8 "In3.Cu" signal "L4VCC")
		(10 "In4.Cu" signal "L5VCC")
		(12 "In5.Cu" signal "L6")
		(14 "In6.Cu" signal "L7GND")
		(2 "B.Cu" signal "BOTTOM")
		(9 "F.Adhes" user "F.Adhesive")
		(11 "B.Adhes" user "B.Adhesive")
		(13 "F.Paste" user "Package Geometry/Pastemask Top")
		(15 "B.Paste" user "Package Geometry/Pastemask Bottom")
		(5 "F.SilkS" user "Ref Des/Silkscreen Top")
		(7 "B.SilkS" user "Ref Des/Silkscreen Bottom")
		(1 "F.Mask" user "Board Geometry/Soldermask Top")
		(3 "B.Mask" user "Board Geometry/Soldermask Bottom")
		(17 "Dwgs.User" user "User.Drawings")
		(19 "Cmts.User" user "User.Comments")
		(21 "Eco1.User" user "User.Eco1")
		(23 "Eco2.User" user "User.Eco2")
		(25 "Edge.Cuts" user "Board Geometry/Outline")
		(27 "Margin" user)
		(31 "F.CrtYd" user "Package Geometry/Place Bound Top")
		(29 "B.CrtYd" user "Package Geometry/Place Bound Bottom")
		(35 "F.Fab" user "Ref Des/Assembly Top")
		(33 "B.Fab" user "Ref Des/Assembly Bottom")
	)
	(footprint ""
		(layer "F.Cu")
		(at 314.20816 -212.420454 180)
		(property "Reference" "C71"
			(at 0 0 180)
			(layer "F.SilkS")
			(hide yes)
			(effects
				(font
					(size 1.27 1.27)
				)
			)
		)
		(property "Value" "SCD22U10V2KX-1GP"
			(at 1.1811 -2.7051 180)
			(unlocked yes)
			(layer "F.Fab")
			(hide yes)
			(effects
				(font
					(size 1.016 1.016)
					(thickness 0.1524)
				)
			)
		)
		(property "Device Type" "C402H22"
			(at 1.1811 -4.2291 180)
			(unlocked yes)
			(layer "F.Fab")
			(hide yes)
			(effects
				(font
					(size 1.016 1.016)
					(thickness 0.1524)
				)
			)
		)
		(duplicate_pad_numbers_are_jumpers no)
		(fp_rect
			(start -0.4318 0.9525)
			(end 0.4318 -0.9525)
			(stroke
				(width 0)
				(type default)
			)
			(fill no)
			(layer "F.CrtYd")
		)
		(fp_rect
			(start -0.4318 0.9525)
			(end 0.4318 -0.9525)
			(stroke
				(width 0)
				(type default)
			)
			(fill no)
			(layer "F.Fab")
		)
		(pad "1" smd custom
			(at 0 -0.4445 180)
			(size 0.1524 0.1524)
			(layers "F.Cu" "F.Mask" "F.Paste")
			(net "PCIE_TX_CAP_N24")
			(options
				(clearance outline)
				(anchor circle)
			)
			(primitives
				(gr_poly
					(pts
						(arc
							(start 0.3048 -0.2032)
							(mid 0.275042 -0.275042)
							(end 0.2032 -0.3048)
						)
						(arc
							(start -0.2032 -0.3048)
							(mid -0.275042 -0.275042)
							(end -0.3048 -0.2032)
						)
						(arc
							(start -0.3048 0.2032)
							(mid -0.275042 0.275042)
							(end -0.2032 0.3048)
						)
						(arc
							(start 0.2032 0.3048)
							(mid 0.275042 0.275042)
							(end 0.3048 0.2032)
						)
					)
					(width 0)
					(fill yes)
				)
			)
		)
		(pad "2" smd custom
			(at 0 0.4445 180)
			(size 0.1524 0.1524)
			(layers "F.Cu" "F.Mask" "F.Paste")
			(net "PCIE_TX_N24")
			(options
				(clearance outline)
				(anchor circle)
			)
			(primitives
				(gr_poly
					(pts
						(arc
							(start 0.3048 -0.2032)
							(mid 0.275042 -0.275042)
							(end 0.2032 -0.3048)
						)
						(arc
							(start -0.2032 -0.3048)
							(mid -0.275042 -0.275042)
							(end -0.3048 -0.2032)
						)
						(arc
							(start -0.3048 0.2032)
							(mid -0.275042 0.275042)
							(end -0.2032 0.3048)
						)
						(arc
							(start 0.2032 0.3048)
							(mid 0.275042 0.275042)
							(end 0.3048 0.2032)
						)
					)
					(width 0)
					(fill yes)
				)
			)
		)
	)
	(footprint ""
		(layer "F.Cu")
		(at 122.547126 -79.269082 -90)
		(property "Reference" "D13"
			(at 0 0 270)
			(layer "F.SilkS")
			(hide yes)
			(effects
				(font
					(size 1.27 1.27)
				)
			)
		)
		(property "Value" "BAT54C-7-F-3-GP"
			(at 0 -5.0292 270)
			(unlocked yes)
			(layer "F.Fab")
			(hide yes)
			(effects
				(font
					(size 1.016 1.016)
					(thickness 0.1524)
				)
			)
		)
		(property "Device Type" "SOT23-2D4-312H48"
			(at 0 -6.5532 270)
			(unlocked yes)
			(layer "F.Fab")
			(hide yes)
			(effects
				(font
					(size 1.016 1.016)
					(thickness 0.1524)
				)
			)
		)
		(duplicate_pad_numbers_are_jumpers no)
		(fp_line
			(start -1.7018 1.778)
			(end -1.7018 -0.9017)
			(stroke
				(width 0.1524)
				(type default)
			)
			(layer "F.SilkS")
		)
		(fp_line
			(start 1.7018 1.778)
			(end -1.7018 1.778)
			(stroke
				(width 0.1524)
				(type default)
			)
			(layer "F.SilkS")
		)
		(fp_line
			(start -1.7018 -0.9017)
			(end -0.635 -0.9017)
			(stroke
				(width 0.1524)
				(type default)
			)
			(layer "F.SilkS")
		)
		(fp_line
			(start -0.635 -0.9017)
			(end -0.635 -1.778)
			(stroke
				(width 0.1524)
				(type default)
			)
			(layer "F.SilkS")
		)
		(fp_line
			(start 0.635 -0.9017)
			(end 1.7018 -0.9017)
			(stroke
				(width 0.1524)
				(type default)
			)
			(layer "F.SilkS")
		)
		(fp_line
			(start 1.7018 -0.9017)
			(end 1.7018 1.778)
			(stroke
				(width 0.1524)
				(type default)
			)
			(layer "F.SilkS")
		)
		(fp_line
			(start -0.635 -1.778)
			(end 0.635 -1.778)
			(stroke
				(width 0.1524)
				(type default)
			)
			(layer "F.SilkS")
		)
		(fp_line
			(start 0.635 -1.778)
			(end 0.635 -0.9017)
			(stroke
				(width 0.1524)
				(type default)
			)
			(layer "F.SilkS")
		)
		(fp_poly
			(pts
				(xy 0.2159 -1.1938) (xy -0.2159 -1.1938) (xy -0.2159 -0.6477) (xy -1.4478 -0.6477) (xy -1.4478 1.1938)
				(xy 1.4478 1.1938) (xy 1.4478 -0.6477) (xy 0.2159 -0.6477)
			)
			(stroke
				(width 0)
				(type default)
			)
			(fill no)
			(layer "F.CrtYd")
		)
		(fp_poly
			(pts
				(xy 1.9558 2.032) (xy 1.9558 -0.1905) (xy 1.4478 -0.1905) (xy 1.4478 1.1938) (xy -1.4478 1.1938)
				(xy -1.4478 -0.6477) (xy -0.2159 -0.6477) (xy -0.2159 -1.1938) (xy 0.2159 -1.1938) (xy 0.2159 -0.6477)
				(xy 1.4478 -0.6477) (xy 1.4478 -0.2032) (xy 1.9558 -0.2032) (xy 1.9558 -1.1557) (xy 0.889 -1.1557)
				(xy 0.889 -2.032) (xy -0.889 -2.032) (xy -0.889 -1.1557) (xy -1.9558 -1.1557) (xy -1.9558 2.032)
			)
			(stroke
				(width 0)
				(type default)
			)
			(fill no)
			(layer "F.CrtYd")
		)
		(fp_poly
			(pts
				(xy -1.9558 2.032) (xy -1.9558 -1.1557) (xy -0.889 -1.1557) (xy -0.889 -2.032) (xy 0.889 -2.032)
				(xy 0.889 -1.1557) (xy 1.9558 -1.1557) (xy 1.9558 2.032)
			)
			(stroke
				(width 0)
				(type default)
			)
			(fill no)
			(layer "F.Fab")
		)
		(pad "1" smd custom
			(at -0.98425 0.9525 270)
			(size 0.1905 0.1905)
			(layers "F.Cu" "F.Mask" "F.Paste")
			(net "P3V3_STBY")
			(options
				(clearance outline)
				(anchor circle)
			)
			(primitives
				(gr_poly
					(pts
						(arc
							(start -0.1778 0.5715)
							(mid -0.321484 0.511984)
							(end -0.381 0.3683)
						)
						(arc
							(start -0.381 -0.3683)
							(mid -0.321484 -0.511984)
							(end -0.1778 -0.5715)
						)
						(arc
							(start 0.1778 -0.5715)
							(mid 0.321484 -0.511984)
							(end 0.381 -0.3683)
						)
						(arc
							(start 0.381 0.3683)
							(mid 0.321484 0.511984)
							(end 0.1778 0.5715)
						)
					)
					(width 0)
					(fill yes)
				)
			)
		)
		(pad "2" smd custom
			(at 0.98425 0.9525 270)
			(size 0.1905 0.1905)
			(layers "F.Cu" "F.Mask" "F.Paste")
			(net "P3V0_BAT_R")
			(options
				(clearance outline)
				(anchor circle)
			)
			(primitives
				(gr_poly
					(pts
						(arc
							(start -0.1778 0.5715)
							(mid -0.321484 0.511984)
							(end -0.381 0.3683)
						)
						(arc
							(start -0.381 -0.3683)
							(mid -0.321484 -0.511984)
							(end -0.1778 -0.5715)
						)
						(arc
							(start 0.1778 -0.5715)
							(mid 0.321484 -0.511984)
							(end 0.381 -0.3683)
						)
						(arc
							(start 0.381 0.3683)
							(mid 0.321484 0.511984)
							(end 0.1778 0.5715)
						)
					)
					(width 0)
					(fill yes)
				)
			)
		)
		(pad "3" smd custom
			(at 0 -0.9525 270)
			(size 0.1905 0.1905)
			(layers "F.Cu" "F.Mask" "F.Paste")
			(net "P3V3_RTC")
			(options
				(clearance outline)
				(anchor circle)
			)
			(primitives
				(gr_poly
					(pts
						(arc
							(start -0.1778 0.5715)
							(mid -0.321484 0.511984)
							(end -0.381 0.3683)
						)
						(arc
							(start -0.381 -0.3683)
							(mid -0.321484 -0.511984)
							(end -0.1778 -0.5715)
						)
						(arc
							(start 0.1778 -0.5715)
							(mid 0.321484 -0.511984)
							(end 0.381 -0.3683)
						)
						(arc
							(start 0.381 0.3683)
							(mid 0.321484 0.511984)
							(end 0.1778 0.5715)
						)
					)
					(width 0)
					(fill yes)
				)
			)
		)
	)
	(footprint ""
		(layer "F.Cu")
		(at 233.68 -23.241)
		(property "Reference" "R816"
			(at 0 0 0)
			(layer "F.SilkS")
			(hide yes)
			(effects
				(font
					(size 1.27 1.27)
				)
			)
		)
		(property "Value" "4K7R2F-GP"
			(at 0.064008 -3.993896 0)
			(unlocked yes)
			(layer "F.Fab")
			(hide yes)
			(effects
				(font
					(size 1.016 1.016)
					(thickness 0.1524)
				)
			)
		)
		(property "Device Type" "R402H16"
			(at 0.064008 -5.517896 0)
			(unlocked yes)
			(layer "F.Fab")
			(hide yes)
			(effects
				(font
					(size 1.016 1.016)
					(thickness 0.1524)
				)
			)
		)
		(duplicate_pad_numbers_are_jumpers no)
		(fp_line
			(start -0.508 -0.9398)
			(end -0.508 0.9398)
			(stroke
				(width 0.1524)
				(type default)
			)
			(layer "F.SilkS")
		)
		(fp_line
			(start 0.508 -0.9398)
			(end -0.508 -0.9398)
			(stroke
				(width 0.1524)
				(type default)
			)
			(layer "F.SilkS")
		)
		(fp_rect
			(start -0.508 0.9398)
			(end 0.508 -0.9398)
			(stroke
				(width 0)
				(type default)
			)
			(fill no)
			(layer "F.CrtYd")
		)
		(fp_rect
			(start -0.508 0.9398)
			(end 0.508 -0.9398)
			(stroke
				(width 0)
				(type default)
			)
			(fill no)
			(layer "F.Fab")
		)
		(pad "1" smd custom
			(at 0 -0.4445)
			(size 0.1397 0.1397)
			(layers "F.Cu" "F.Mask" "F.Paste")
			(net "GND")
			(options
				(clearance outline)
				(anchor circle)
			)
			(primitives
				(gr_poly
					(pts
						(arc
							(start -0.1778 -0.2794)
							(mid -0.249642 -0.249642)
							(end -0.2794 -0.1778)
						)
						(arc
							(start -0.2794 0.1778)
							(mid -0.249642 0.249642)
							(end -0.1778 0.2794)
						)
						(arc
							(start 0.1778 0.2794)
							(mid 0.249642 0.249642)
							(end 0.2794 0.1778)
						)
						(arc
							(start 0.2794 -0.1778)
							(mid 0.249642 -0.249642)
							(end 0.1778 -0.2794)
						)
					)
					(width 0)
					(fill yes)
				)
			)
		)
		(pad "2" smd custom
			(at 0 0.4445)
			(size 0.1397 0.1397)
			(layers "F.Cu" "F.Mask" "F.Paste")
			(net "BOOTSTRAP8")
			(options
				(clearance outline)
				(anchor circle)
			)
			(primitives
				(gr_poly
					(pts
						(arc
							(start -0.1778 -0.2794)
							(mid -0.249642 -0.249642)
							(end -0.2794 -0.1778)
						)
						(arc
							(start -0.2794 0.1778)
							(mid -0.249642 0.249642)
							(end -0.1778 0.2794)
						)
						(arc
							(start 0.1778 0.2794)
							(mid 0.249642 0.249642)
							(end 0.2794 0.1778)
						)
						(arc
							(start 0.2794 -0.1778)
							(mid 0.249642 -0.249642)
							(end 0.1778 -0.2794)
						)
					)
					(width 0)
					(fill yes)
				)
			)
		)
	)
	(footprint ""
		(layer "F.Cu")
		(at 283.592016 -212.420454 180)
		(property "Reference" "C94"
			(at 0 0 180)
			(layer "F.SilkS")
			(hide yes)
			(effects
				(font
					(size 1.27 1.27)
				)
			)
		)
		(property "Value" "SCD22U10V2KX-1GP"
			(at 1.1811 -2.7051 180)
			(unlocked yes)
			(layer "F.Fab")
			(hide yes)
			(effects
				(font
					(size 1.016 1.016)
					(thickness 0.1524)
				)
			)
		)
		(property "Device Type" "C402H22"
			(at 1.1811 -4.2291 180)
			(unlocked yes)
			(layer "F.Fab")
			(hide yes)
			(effects
				(font
					(size 1.016 1.016)
					(thickness 0.1524)
				)
			)
		)
		(duplicate_pad_numbers_are_jumpers no)
		(fp_rect
			(start -0.4318 0.9525)
			(end 0.4318 -0.9525)
			(stroke
				(width 0)
				(type default)
			)
			(fill no)
			(layer "F.CrtYd")
		)
		(fp_rect
			(start -0.4318 0.9525)
			(end 0.4318 -0.9525)
			(stroke
				(width 0)
				(type default)
			)
			(fill no)
			(layer "F.Fab")
		)
		(pad "1" smd custom
			(at 0 -0.4445 180)
			(size 0.1524 0.1524)
			(layers "F.Cu" "F.Mask" "F.Paste")
			(net "PCIE_TX_CAP_P31")
			(options
				(clearance outline)
				(anchor circle)
			)
			(primitives
				(gr_poly
					(pts
						(arc
							(start 0.3048 -0.2032)
							(mid 0.275042 -0.275042)
							(end 0.2032 -0.3048)
						)
						(arc
							(start -0.2032 -0.3048)
							(mid -0.275042 -0.275042)
							(end -0.3048 -0.2032)
						)
						(arc
							(start -0.3048 0.2032)
							(mid -0.275042 0.275042)
							(end -0.2032 0.3048)
						)
						(arc
							(start 0.2032 0.3048)
							(mid 0.275042 0.275042)
							(end 0.3048 0.2032)
						)
					)
					(width 0)
					(fill yes)
				)
			)
		)
		(pad "2" smd custom
			(at 0 0.4445 180)
			(size 0.1524 0.1524)
			(layers "F.Cu" "F.Mask" "F.Paste")
			(net "PCIE_TX_P31")
			(options
				(clearance outline)
				(anchor circle)
			)
			(primitives
				(gr_poly
					(pts
						(arc
							(start 0.3048 -0.2032)
							(mid 0.275042 -0.275042)
							(end 0.2032 -0.3048)
						)
						(arc
							(start -0.2032 -0.3048)
							(mid -0.275042 -0.275042)
							(end -0.3048 -0.2032)
						)
						(arc
							(start -0.3048 0.2032)
							(mid -0.275042 0.275042)
							(end -0.2032 0.3048)
						)
						(arc
							(start 0.2032 0.3048)
							(mid 0.275042 0.275042)
							(end 0.3048 0.2032)
						)
					)
					(width 0)
					(fill yes)
				)
			)
		)
	)
	(footprint ""
		(layer "F.Cu")
		(at 132.816346 -59.750198 180)
		(property "Reference" "R458"
			(at 0 0 180)
			(layer "F.SilkS")
			(hide yes)
			(effects
				(font
					(size 1.27 1.27)
				)
			)
		)
		(property "Value" "100KR2F-L1-GP"
			(at 0.064008 -3.993896 180)
			(unlocked yes)
			(layer "F.Fab")
			(hide yes)
			(effects
				(font
					(size 1.016 1.016)
					(thickness 0.1524)
				)
			)
		)
		(property "Device Type" "R402H16"
			(at 0.064008 -5.517896 180)
			(unlocked yes)
			(layer "F.Fab")
			(hide yes)
			(effects
				(font
					(size 1.016 1.016)
					(thickness 0.1524)
				)
			)
		)
		(duplicate_pad_numbers_are_jumpers no)
		(fp_line
			(start 0.508 -0.9398)
			(end -0.508 -0.9398)
			(stroke
				(width 0.1524)
				(type default)
			)
			(layer "F.SilkS")
		)
		(fp_line
			(start -0.508 -0.9398)
			(end -0.508 0.9398)
			(stroke
				(width 0.1524)
				(type default)
			)
			(layer "F.SilkS")
		)
		(fp_rect
			(start -0.508 0.9398)
			(end 0.508 -0.9398)
			(stroke
				(width 0)
				(type default)
			)
			(fill no)
			(layer "F.CrtYd")
		)
		(fp_rect
			(start -0.508 0.9398)
			(end 0.508 -0.9398)
			(stroke
				(width 0)
				(type default)
			)
			(fill no)
			(layer "F.Fab")
		)
		(pad "1" smd custom
			(at 0 -0.4445 180)
			(size 0.1397 0.1397)
			(layers "F.Cu" "F.Mask" "F.Paste")
			(net "DUT_VDDO")
			(options
				(clearance outline)
				(anchor circle)
			)
			(primitives
				(gr_poly
					(pts
						(arc
							(start -0.1778 -0.2794)
							(mid -0.249642 -0.249642)
							(end -0.2794 -0.1778)
						)
						(arc
							(start -0.2794 0.1778)
							(mid -0.249642 0.249642)
							(end -0.1778 0.2794)
						)
						(arc
							(start 0.1778 0.2794)
							(mid 0.249642 0.249642)
							(end 0.2794 0.1778)
						)
						(arc
							(start 0.2794 -0.1778)
							(mid 0.249642 -0.249642)
							(end 0.1778 -0.2794)
						)
					)
					(width 0)
					(fill yes)
				)
			)
		)
		(pad "2" smd custom
			(at 0 0.4445 180)
			(size 0.1397 0.1397)
			(layers "F.Cu" "F.Mask" "F.Paste")
			(net "SPI_DATA0_1_R")
			(options
				(clearance outline)
				(anchor circle)
			)
			(primitives
				(gr_poly
					(pts
						(arc
							(start -0.1778 -0.2794)
							(mid -0.249642 -0.249642)
							(end -0.2794 -0.1778)
						)
						(arc
							(start -0.2794 0.1778)
							(mid -0.249642 0.249642)
							(end -0.1778 0.2794)
						)
						(arc
							(start 0.1778 0.2794)
							(mid 0.249642 0.249642)
							(end 0.2794 0.1778)
						)
						(arc
							(start 0.2794 -0.1778)
							(mid 0.249642 -0.249642)
							(end 0.1778 -0.2794)
						)
					)
					(width 0)
					(fill yes)
				)
			)
		)
	)
	(footprint ""
		(layer "F.Cu")
		(at 42.0878 -191.3636 90)
		(property "Reference" "R871"
			(at 0 0 90)
			(layer "F.SilkS")
			(hide yes)
			(effects
				(font
					(size 1.27 1.27)
				)
			)
		)
		(property "Value" "2KR2F-3-GP"
			(at 0.064008 -3.993896 90)
			(unlocked yes)
			(layer "F.Fab")
			(hide yes)
			(effects
				(font
					(size 1.016 1.016)
					(thickness 0.1524)
				)
			)
		)
		(property "Device Type" "R402H16"
			(at 0.064008 -5.517896 90)
			(unlocked yes)
			(layer "F.Fab")
			(hide yes)
			(effects
				(font
					(size 1.016 1.016)
					(thickness 0.1524)
				)
			)
		)
		(duplicate_pad_numbers_are_jumpers no)
		(fp_line
			(start 0.508 -0.9398)
			(end -0.508 -0.9398)
			(stroke
				(width 0.1524)
				(type default)
			)
			(layer "F.SilkS")
		)
		(fp_line
			(start -0.508 -0.9398)
			(end -0.508 0.9398)
			(stroke
				(width 0.1524)
				(type default)
			)
			(layer "F.SilkS")
		)
		(fp_rect
			(start -0.508 0.9398)
			(end 0.508 -0.9398)
			(stroke
				(width 0)
				(type default)
			)
			(fill no)
			(layer "F.CrtYd")
		)
		(fp_rect
			(start -0.508 0.9398)
			(end 0.508 -0.9398)
			(stroke
				(width 0)
				(type default)
			)
			(fill no)
			(layer "F.Fab")
		)
		(pad "1" smd custom
			(at 0 -0.4445 90)
			(size 0.1397 0.1397)
			(layers "F.Cu" "F.Mask" "F.Paste")
			(net "P3V3_STBY")
			(options
				(clearance outline)
				(anchor circle)
			)
			(primitives
				(gr_poly
					(pts
						(arc
							(start -0.1778 -0.2794)
							(mid -0.249642 -0.249642)
							(end -0.2794 -0.1778)
						)
						(arc
							(start -0.2794 0.1778)
							(mid -0.249642 0.249642)
							(end -0.1778 0.2794)
						)
						(arc
							(start 0.1778 0.2794)
							(mid 0.249642 0.249642)
							(end 0.2794 0.1778)
						)
						(arc
							(start 0.2794 -0.1778)
							(mid 0.249642 -0.249642)
							(end 0.1778 -0.2794)
						)
					)
					(width 0)
					(fill yes)
				)
			)
		)
		(pad "2" smd custom
			(at 0 0.4445 90)
			(size 0.1397 0.1397)
			(layers "F.Cu" "F.Mask" "F.Paste")
			(net "BUF_I2C9_CLKBUF2_SDA_R")
			(options
				(clearance outline)
				(anchor circle)
			)
			(primitives
				(gr_poly
					(pts
						(arc
							(start -0.1778 -0.2794)
							(mid -0.249642 -0.249642)
							(end -0.2794 -0.1778)
						)
						(arc
							(start -0.2794 0.1778)
							(mid -0.249642 0.249642)
							(end -0.1778 0.2794)
						)
						(arc
							(start 0.1778 0.2794)
							(mid 0.249642 0.249642)
							(end 0.2794 0.1778)
						)
						(arc
							(start 0.2794 -0.1778)
							(mid 0.249642 -0.249642)
							(end 0.1778 -0.2794)
						)
					)
					(width 0)
					(fill yes)
				)
			)
		)
	)
)
